(kicad_pcb
	(version 20260206)
	(generator "pcbnew")
	(generator_version "10.0")
	(general
		(thickness 1.6)
		(legacy_teardrops no)
	)
	(paper "A4")
	(title_block
		(title "panther-plus-userver — 13130-1b_20150205.brd")
		(comment 1 "Honey Badger (Wiwynn) / footprints 934-941 of 1509")
	)
	(layers
		(0 "F.Cu" signal "TOP")
		(4 "In1.Cu" signal "L2")
		(6 "In2.Cu" signal "L3")
		(8 "In3.Cu" signal "L4")
		(10 "In4.Cu" signal "L5")
		(12 "In5.Cu" signal "L6")
		(14 "In6.Cu" signal "L7")
		(16 "In7.Cu" signal "L8")
		(18 "In8.Cu" signal "L9")
		(20 "In9.Cu" signal "L10")
		(22 "In10.Cu" signal "L11")
		(2 "B.Cu" signal "BOTTOM")
		(9 "F.Adhes" user "F.Adhesive")
		(11 "B.Adhes" user "B.Adhesive")
		(13 "F.Paste" user "Package Geometry/Pastemask Top")
		(15 "B.Paste" user "Package Geometry/Pastemask Bottom")
		(5 "F.SilkS" user "Ref Des/Silkscreen Top")
		(7 "B.SilkS" user "Ref Des/Silkscreen Bottom")
		(1 "F.Mask" user "Board Geometry/Soldermask Top")
		(3 "B.Mask" user "Board Geometry/Soldermask Bottom")
		(17 "Dwgs.User" user "User.Drawings")
		(19 "Cmts.User" user "User.Comments")
		(21 "Eco1.User" user "User.Eco1")
		(23 "Eco2.User" user "User.Eco2")
		(25 "Edge.Cuts" user "Board Geometry/Outline")
		(27 "Margin" user)
		(31 "F.CrtYd" user "Package Geometry/Place Bound Top")
		(29 "B.CrtYd" user "Package Geometry/Place Bound Bottom")
		(35 "F.Fab" user "Ref Des/Assembly Top")
		(33 "B.Fab" user "Ref Des/Assembly Bottom")
	)
	(footprint ""
		(layer "B.Cu")
		(at 88.265 -34.9504)
		(property "Reference" "R502"
			(at 0 0 0)
			(layer "B.SilkS")
			(hide yes)
			(effects
				(font
					(size 1.27 1.27)
				)
				(justify mirror)
			)
		)
		(property "Value" "4K7R2F-GP"
			(at -1.7907 -1.1176 0)
			(unlocked yes)
			(layer "B.Fab")
			(hide yes)
			(effects
				(font
					(size 1.016 1.016)
					(thickness 0.1524)
				)
				(justify mirror)
			)
		)
		(property "Device Type" "R402H16"
			(at -1.7907 -2.6416 0)
			(unlocked yes)
			(layer "B.Fab")
			(hide yes)
			(effects
				(font
					(size 1.016 1.016)
					(thickness 0.1524)
				)
				(justify mirror)
			)
		)
		(duplicate_pad_numbers_are_jumpers no)
		(fp_rect
			(start 0.381 0.8382)
			(end -0.381 -0.8382)
			(stroke
				(width 0)
				(type default)
			)
			(fill no)
			(layer "B.CrtYd")
		)
		(fp_rect
			(start 0.381 0.8382)
			(end -0.381 -0.8382)
			(stroke
				(width 0)
				(type default)
			)
			(fill no)
			(layer "B.Fab")
		)
		(pad "1" smd custom
			(at 0 -0.4318 180)
			(size 0.127 0.127)
			(layers "B.Cu" "B.Mask" "B.Paste")
			(net "P3V3_CPU")
			(options
				(clearance outline)
				(anchor circle)
			)
			(primitives
				(gr_poly
					(pts
						(arc
							(start -0.2032 0.2794)
							(mid -0.239121 0.264521)
							(end -0.254 0.2286)
						)
						(arc
							(start -0.254 -0.2286)
							(mid -0.239121 -0.264521)
							(end -0.2032 -0.2794)
						)
						(arc
							(start 0.2032 -0.2794)
							(mid 0.239121 -0.264521)
							(end 0.254 -0.2286)
						)
						(arc
							(start 0.254 0.2286)
							(mid 0.239121 0.264521)
							(end 0.2032 0.2794)
						)
					)
					(width 0)
					(fill yes)
				)
			)
		)
		(pad "2" smd custom
			(at 0 0.4318 180)
			(size 0.127 0.127)
			(layers "B.Cu" "B.Mask" "B.Paste")
			(net "BD_REV_1")
			(options
				(clearance outline)
				(anchor circle)
			)
			(primitives
				(gr_poly
					(pts
						(arc
							(start -0.2032 0.2794)
							(mid -0.239121 0.264521)
							(end -0.254 0.2286)
						)
						(arc
							(start -0.254 -0.2286)
							(mid -0.239121 -0.264521)
							(end -0.2032 -0.2794)
						)
						(arc
							(start 0.2032 -0.2794)
							(mid 0.239121 -0.264521)
							(end 0.254 -0.2286)
						)
						(arc
							(start 0.254 0.2286)
							(mid 0.239121 0.264521)
							(end 0.2032 0.2794)
						)
					)
					(width 0)
					(fill yes)
				)
			)
		)
	)
	(footprint ""
		(layer "B.Cu")
		(at 159.131 -12.447778 180)
		(property "Reference" "C299"
			(at 0 0 0)
			(layer "B.SilkS")
			(hide yes)
			(effects
				(font
					(size 1.27 1.27)
				)
				(justify mirror)
			)
		)
		(property "Value" "SC1U10V2KX-1GP"
			(at -1.8923 -1.2065 180)
			(unlocked yes)
			(layer "B.Fab")
			(hide yes)
			(effects
				(font
					(size 1.016 1.016)
					(thickness 0.1524)
				)
				(justify mirror)
			)
		)
		(property "Device Type" "C402H22"
			(at -1.8923 -2.7305 180)
			(unlocked yes)
			(layer "B.Fab")
			(hide yes)
			(effects
				(font
					(size 1.016 1.016)
					(thickness 0.1524)
				)
				(justify mirror)
			)
		)
		(duplicate_pad_numbers_are_jumpers no)
		(fp_rect
			(start 0.381 0.7366)
			(end -0.381 -0.7366)
			(stroke
				(width 0)
				(type default)
			)
			(fill no)
			(layer "B.CrtYd")
		)
		(fp_rect
			(start 0.381 0.7366)
			(end -0.381 -0.7366)
			(stroke
				(width 0)
				(type default)
			)
			(fill no)
			(layer "B.Fab")
		)
		(pad "1" smd custom
			(at 0 -0.4572)
			(size 0.1143 0.1143)
			(layers "B.Cu" "B.Mask" "B.Paste")
			(net "PV_VDDR")
			(options
				(clearance outline)
				(anchor circle)
			)
			(primitives
				(gr_poly
					(pts
						(arc
							(start -0.254 0.1778)
							(mid -0.239121 0.213721)
							(end -0.2032 0.2286)
						)
						(arc
							(start 0.2032 0.2286)
							(mid 0.239121 0.213721)
							(end 0.254 0.1778)
						)
						(arc
							(start 0.254 -0.1778)
							(mid 0.239121 -0.213721)
							(end 0.2032 -0.2286)
						)
						(arc
							(start -0.2032 -0.2286)
							(mid -0.239121 -0.213721)
							(end -0.254 -0.1778)
						)
					)
					(width 0)
					(fill yes)
				)
			)
		)
		(pad "2" smd custom
			(at 0 0.4572)
			(size 0.1143 0.1143)
			(layers "B.Cu" "B.Mask" "B.Paste")
			(net "GND")
			(options
				(clearance outline)
				(anchor circle)
			)
			(primitives
				(gr_poly
					(pts
						(arc
							(start -0.254 0.1778)
							(mid -0.239121 0.213721)
							(end -0.2032 0.2286)
						)
						(arc
							(start 0.2032 0.2286)
							(mid 0.239121 0.213721)
							(end 0.254 0.1778)
						)
						(arc
							(start 0.254 -0.1778)
							(mid 0.239121 -0.213721)
							(end 0.2032 -0.2286)
						)
						(arc
							(start -0.2032 -0.2286)
							(mid -0.239121 -0.213721)
							(end -0.254 -0.1778)
						)
					)
					(width 0)
					(fill yes)
				)
			)
		)
	)
	(footprint ""
		(layer "B.Cu")
		(at 26.289 -32.385 180)
		(property "Reference" "PC47"
			(at 0 0 0)
			(layer "B.SilkS")
			(hide yes)
			(effects
				(font
					(size 1.27 1.27)
				)
				(justify mirror)
			)
		)
		(property "Value" "SC22U6D3V3MX-1-GP"
			(at 0.0254 -2.0193 180)
			(unlocked yes)
			(layer "B.Fab")
			(hide yes)
			(effects
				(font
					(size 1.016 1.016)
					(thickness 0.1524)
				)
				(justify mirror)
			)
		)
		(property "Device Type" "C603H40"
			(at 0.0254 -3.5433 180)
			(unlocked yes)
			(layer "B.Fab")
			(hide yes)
			(effects
				(font
					(size 1.016 1.016)
					(thickness 0.1524)
				)
				(justify mirror)
			)
		)
		(duplicate_pad_numbers_are_jumpers no)
		(fp_line
			(start 0.4064 0)
			(end -0.4064 0)
			(stroke
				(width 0.2286)
				(type default)
			)
			(layer "B.SilkS")
		)
		(fp_rect
			(start 0.635 1.1811)
			(end -0.635 -1.1811)
			(stroke
				(width 0)
				(type default)
			)
			(fill no)
			(layer "B.CrtYd")
		)
		(fp_rect
			(start 0.635 1.1811)
			(end -0.635 -1.1811)
			(stroke
				(width 0)
				(type default)
			)
			(fill no)
			(layer "B.Fab")
		)
		(pad "1" smd custom
			(at 0 -0.6604)
			(size 0.19685 0.19685)
			(layers "B.Cu" "B.Mask" "B.Paste")
			(net "P1V0")
			(options
				(clearance outline)
				(anchor circle)
			)
			(primitives
				(gr_poly
					(pts
						(arc
							(start 0.508 0.2921)
							(mid 0.478242 0.363942)
							(end 0.4064 0.3937)
						)
						(arc
							(start -0.4064 0.3937)
							(mid -0.478242 0.363942)
							(end -0.508 0.2921)
						)
						(arc
							(start -0.508 -0.2921)
							(mid -0.478242 -0.363942)
							(end -0.4064 -0.3937)
						)
						(arc
							(start 0.4064 -0.3937)
							(mid 0.478242 -0.363942)
							(end 0.508 -0.2921)
						)
					)
					(width 0)
					(fill yes)
				)
			)
		)
		(pad "2" smd custom
			(at 0 0.6604)
			(size 0.19685 0.19685)
			(layers "B.Cu" "B.Mask" "B.Paste")
			(net "GND")
			(options
				(clearance outline)
				(anchor circle)
			)
			(primitives
				(gr_poly
					(pts
						(arc
							(start 0.508 0.2921)
							(mid 0.478242 0.363942)
							(end 0.4064 0.3937)
						)
						(arc
							(start -0.4064 0.3937)
							(mid -0.478242 0.363942)
							(end -0.508 0.2921)
						)
						(arc
							(start -0.508 -0.2921)
							(mid -0.478242 -0.363942)
							(end -0.4064 -0.3937)
						)
						(arc
							(start 0.4064 -0.3937)
							(mid 0.478242 -0.363942)
							(end 0.508 -0.2921)
						)
					)
					(width 0)
					(fill yes)
				)
			)
		)
	)
	(footprint ""
		(layer "B.Cu")
		(at 58.039 -15.24 -90)
		(property "Reference" "R434"
			(at 0 0 90)
			(layer "B.SilkS")
			(hide yes)
			(effects
				(font
					(size 1.27 1.27)
				)
				(justify mirror)
			)
		)
		(property "Value" "1KR2F-3-GP"
			(at -1.7907 -1.1176 270)
			(unlocked yes)
			(layer "B.Fab")
			(hide yes)
			(effects
				(font
					(size 1.016 1.016)
					(thickness 0.1524)
				)
				(justify mirror)
			)
		)
		(property "Device Type" "R402H16"
			(at -1.7907 -2.6416 270)
			(unlocked yes)
			(layer "B.Fab")
			(hide yes)
			(effects
				(font
					(size 1.016 1.016)
					(thickness 0.1524)
				)
				(justify mirror)
			)
		)
		(duplicate_pad_numbers_are_jumpers no)
		(fp_rect
			(start 0.381 0.8382)
			(end -0.381 -0.8382)
			(stroke
				(width 0)
				(type default)
			)
			(fill no)
			(layer "B.CrtYd")
		)
		(fp_rect
			(start 0.381 0.8382)
			(end -0.381 -0.8382)
			(stroke
				(width 0)
				(type default)
			)
			(fill no)
			(layer "B.Fab")
		)
		(pad "1" smd custom
			(at 0 -0.4318 90)
			(size 0.127 0.127)
			(layers "B.Cu" "B.Mask" "B.Paste")
			(net "P3V3")
			(options
				(clearance outline)
				(anchor circle)
			)
			(primitives
				(gr_poly
					(pts
						(arc
							(start -0.2032 0.2794)
							(mid -0.239121 0.264521)
							(end -0.254 0.2286)
						)
						(arc
							(start -0.254 -0.2286)
							(mid -0.239121 -0.264521)
							(end -0.2032 -0.2794)
						)
						(arc
							(start 0.2032 -0.2794)
							(mid 0.239121 -0.264521)
							(end 0.254 -0.2286)
						)
						(arc
							(start 0.254 0.2286)
							(mid 0.239121 0.264521)
							(end 0.2032 0.2794)
						)
					)
					(width 0)
					(fill yes)
				)
			)
		)
		(pad "2" smd custom
			(at 0 0.4318 90)
			(size 0.127 0.127)
			(layers "B.Cu" "B.Mask" "B.Paste")
			(net "PMU_BUF_PLTRST#")
			(options
				(clearance outline)
				(anchor circle)
			)
			(primitives
				(gr_poly
					(pts
						(arc
							(start -0.2032 0.2794)
							(mid -0.239121 0.264521)
							(end -0.254 0.2286)
						)
						(arc
							(start -0.254 -0.2286)
							(mid -0.239121 -0.264521)
							(end -0.2032 -0.2794)
						)
						(arc
							(start 0.2032 -0.2794)
							(mid 0.239121 -0.264521)
							(end 0.254 -0.2286)
						)
						(arc
							(start 0.254 0.2286)
							(mid 0.239121 0.264521)
							(end 0.2032 0.2794)
						)
					)
					(width 0)
					(fill yes)
				)
			)
		)
	)
	(footprint ""
		(layer "B.Cu")
		(at 15.875 -23.114 -90)
		(property "Reference" "PR90"
			(at 0 0 90)
			(layer "B.SilkS")
			(hide yes)
			(effects
				(font
					(size 1.27 1.27)
				)
				(justify mirror)
			)
		)
		(property "Value" "10KR2F-2-GP"
			(at -1.7907 -1.1176 270)
			(unlocked yes)
			(layer "B.Fab")
			(hide yes)
			(effects
				(font
					(size 1.016 1.016)
					(thickness 0.1524)
				)
				(justify mirror)
			)
		)
		(property "Device Type" "R402H16"
			(at -1.7907 -2.6416 270)
			(unlocked yes)
			(layer "B.Fab")
			(hide yes)
			(effects
				(font
					(size 1.016 1.016)
					(thickness 0.1524)
				)
				(justify mirror)
			)
		)
		(duplicate_pad_numbers_are_jumpers no)
		(fp_rect
			(start 0.381 0.8382)
			(end -0.381 -0.8382)
			(stroke
				(width 0)
				(type default)
			)
			(fill no)
			(layer "B.CrtYd")
		)
		(fp_rect
			(start 0.381 0.8382)
			(end -0.381 -0.8382)
			(stroke
				(width 0)
				(type default)
			)
			(fill no)
			(layer "B.Fab")
		)
		(pad "1" smd custom
			(at 0 -0.4318 90)
			(size 0.127 0.127)
			(layers "B.Cu" "B.Mask" "B.Paste")
			(net "PG_P1V0")
			(options
				(clearance outline)
				(anchor circle)
			)
			(primitives
				(gr_poly
					(pts
						(arc
							(start -0.2032 0.2794)
							(mid -0.239121 0.264521)
							(end -0.254 0.2286)
						)
						(arc
							(start -0.254 -0.2286)
							(mid -0.239121 -0.264521)
							(end -0.2032 -0.2794)
						)
						(arc
							(start 0.2032 -0.2794)
							(mid 0.239121 -0.264521)
							(end 0.254 -0.2286)
						)
						(arc
							(start 0.254 0.2286)
							(mid 0.239121 0.264521)
							(end 0.2032 0.2794)
						)
					)
					(width 0)
					(fill yes)
				)
			)
		)
		(pad "2" smd custom
			(at 0 0.4318 90)
			(size 0.127 0.127)
			(layers "B.Cu" "B.Mask" "B.Paste")
			(net "P1V0_VREG")
			(options
				(clearance outline)
				(anchor circle)
			)
			(primitives
				(gr_poly
					(pts
						(arc
							(start -0.2032 0.2794)
							(mid -0.239121 0.264521)
							(end -0.254 0.2286)
						)
						(arc
							(start -0.254 -0.2286)
							(mid -0.239121 -0.264521)
							(end -0.2032 -0.2794)
						)
						(arc
							(start 0.2032 -0.2794)
							(mid 0.239121 -0.264521)
							(end 0.254 -0.2286)
						)
						(arc
							(start 0.254 0.2286)
							(mid 0.239121 0.264521)
							(end 0.2032 0.2794)
						)
					)
					(width 0)
					(fill yes)
				)
			)
		)
	)
	(footprint ""
		(layer "B.Cu")
		(at 38.989 -49.6062 90)
		(property "Reference" "R128"
			(at 0 0 90)
			(layer "B.SilkS")
			(hide yes)
			(effects
				(font
					(size 1.27 1.27)
				)
				(justify mirror)
			)
		)
		(property "Value" "0R2J-2-GP"
			(at -1.7907 -1.1176 90)
			(unlocked yes)
			(layer "B.Fab")
			(hide yes)
			(effects
				(font
					(size 1.016 1.016)
					(thickness 0.1524)
				)
				(justify mirror)
			)
		)
		(property "Device Type" "R402H16"
			(at -1.7907 -2.6416 90)
			(unlocked yes)
			(layer "B.Fab")
			(hide yes)
			(effects
				(font
					(size 1.016 1.016)
					(thickness 0.1524)
				)
				(justify mirror)
			)
		)
		(duplicate_pad_numbers_are_jumpers no)
		(fp_rect
			(start 0.381 0.8382)
			(end -0.381 -0.8382)
			(stroke
				(width 0)
				(type default)
			)
			(fill no)
			(layer "B.CrtYd")
		)
		(fp_rect
			(start 0.381 0.8382)
			(end -0.381 -0.8382)
			(stroke
				(width 0)
				(type default)
			)
			(fill no)
			(layer "B.Fab")
		)
		(pad "1" smd custom
			(at 0 -0.4318 270)
			(size 0.127 0.127)
			(layers "B.Cu" "B.Mask" "B.Paste")
			(net "SMB_HOST_LV_DATA")
			(options
				(clearance outline)
				(anchor circle)
			)
			(primitives
				(gr_poly
					(pts
						(arc
							(start -0.2032 0.2794)
							(mid -0.239121 0.264521)
							(end -0.254 0.2286)
						)
						(arc
							(start -0.254 -0.2286)
							(mid -0.239121 -0.264521)
							(end -0.2032 -0.2794)
						)
						(arc
							(start 0.2032 -0.2794)
							(mid 0.239121 -0.264521)
							(end 0.254 -0.2286)
						)
						(arc
							(start 0.254 0.2286)
							(mid 0.239121 0.264521)
							(end 0.2032 0.2794)
						)
					)
					(width 0)
					(fill yes)
				)
			)
		)
		(pad "2" smd custom
			(at 0 0.4318 270)
			(size 0.127 0.127)
			(layers "B.Cu" "B.Mask" "B.Paste")
			(net "SMB_CLKGEN_R_DATA")
			(options
				(clearance outline)
				(anchor circle)
			)
			(primitives
				(gr_poly
					(pts
						(arc
							(start -0.2032 0.2794)
							(mid -0.239121 0.264521)
							(end -0.254 0.2286)
						)
						(arc
							(start -0.254 -0.2286)
							(mid -0.239121 -0.264521)
							(end -0.2032 -0.2794)
						)
						(arc
							(start 0.2032 -0.2794)
							(mid 0.239121 -0.264521)
							(end 0.254 -0.2286)
						)
						(arc
							(start 0.254 0.2286)
							(mid 0.239121 0.264521)
							(end 0.2032 0.2794)
						)
					)
					(width 0)
					(fill yes)
				)
			)
		)
	)
	(footprint ""
		(layer "B.Cu")
		(at 78.867 -15.748)
		(property "Reference" "PC205"
			(at 0 0 0)
			(layer "B.SilkS")
			(hide yes)
			(effects
				(font
					(size 1.27 1.27)
				)
				(justify mirror)
			)
		)
		(property "Value" "SCD1U16V2KX-3GP"
			(at -1.1811 -2.7051 0)
			(unlocked yes)
			(layer "B.Fab")
			(hide yes)
			(effects
				(font
					(size 1.016 1.016)
					(thickness 0.1524)
				)
				(justify mirror)
			)
		)
		(property "Device Type" "C402H22"
			(at -1.1811 -4.2291 0)
			(unlocked yes)
			(layer "B.Fab")
			(hide yes)
			(effects
				(font
					(size 1.016 1.016)
					(thickness 0.1524)
				)
				(justify mirror)
			)
		)
		(duplicate_pad_numbers_are_jumpers no)
		(fp_rect
			(start 0.381 0.7366)
			(end -0.381 -0.7366)
			(stroke
				(width 0)
				(type default)
			)
			(fill no)
			(layer "B.CrtYd")
		)
		(fp_rect
			(start 0.381 0.7366)
			(end -0.381 -0.7366)
			(stroke
				(width 0)
				(type default)
			)
			(fill no)
			(layer "B.Fab")
		)
		(pad "1" smd custom
			(at 0 -0.4572 180)
			(size 0.1143 0.1143)
			(layers "B.Cu" "B.Mask" "B.Paste")
			(net "TPS74801_P1V35_IN")
			(options
				(clearance outline)
				(anchor circle)
			)
			(primitives
				(gr_poly
					(pts
						(arc
							(start -0.254 0.1778)
							(mid -0.239121 0.213721)
							(end -0.2032 0.2286)
						)
						(arc
							(start 0.2032 0.2286)
							(mid 0.239121 0.213721)
							(end 0.254 0.1778)
						)
						(arc
							(start 0.254 -0.1778)
							(mid 0.239121 -0.213721)
							(end 0.2032 -0.2286)
						)
						(arc
							(start -0.2032 -0.2286)
							(mid -0.239121 -0.213721)
							(end -0.254 -0.1778)
						)
					)
					(width 0)
					(fill yes)
				)
			)
		)
		(pad "2" smd custom
			(at 0 0.4572 180)
			(size 0.1143 0.1143)
			(layers "B.Cu" "B.Mask" "B.Paste")
			(net "GND")
			(options
				(clearance outline)
				(anchor circle)
			)
			(primitives
				(gr_poly
					(pts
						(arc
							(start -0.254 0.1778)
							(mid -0.239121 0.213721)
							(end -0.2032 0.2286)
						)
						(arc
							(start 0.2032 0.2286)
							(mid 0.239121 0.213721)
							(end 0.254 0.1778)
						)
						(arc
							(start 0.254 -0.1778)
							(mid 0.239121 -0.213721)
							(end 0.2032 -0.2286)
						)
						(arc
							(start -0.2032 -0.2286)
							(mid -0.239121 -0.213721)
							(end -0.254 -0.1778)
						)
					)
					(width 0)
					(fill yes)
				)
			)
		)
	)
	(footprint ""
		(layer "B.Cu")
		(at 93.599 -25.4 90)
		(property "Reference" "C246"
			(at 0 0 90)
			(layer "B.SilkS")
			(hide yes)
			(effects
				(font
					(size 1.27 1.27)
				)
				(justify mirror)
			)
		)
		(property "Value" "SC1U10V2KX-1GP"
			(at -1.1811 -2.7051 90)
			(unlocked yes)
			(layer "B.Fab")
			(hide yes)
			(effects
				(font
					(size 1.016 1.016)
					(thickness 0.1524)
				)
				(justify mirror)
			)
		)
		(property "Device Type" "C402H22"
			(at -1.1811 -4.2291 90)
			(unlocked yes)
			(layer "B.Fab")
			(hide yes)
			(effects
				(font
					(size 1.016 1.016)
					(thickness 0.1524)
				)
				(justify mirror)
			)
		)
		(duplicate_pad_numbers_are_jumpers no)
		(fp_rect
			(start 0.381 0.7366)
			(end -0.381 -0.7366)
			(stroke
				(width 0)
				(type default)
			)
			(fill no)
			(layer "B.CrtYd")
		)
		(fp_rect
			(start 0.381 0.7366)
			(end -0.381 -0.7366)
			(stroke
				(width 0)
				(type default)
			)
			(fill no)
			(layer "B.Fab")
		)
		(pad "1" smd custom
			(at 0 -0.4572 270)
			(size 0.1143 0.1143)
			(layers "B.Cu" "B.Mask" "B.Paste")
			(net "P1V0")
			(options
				(clearance outline)
				(anchor circle)
			)
			(primitives
				(gr_poly
					(pts
						(arc
							(start -0.254 0.1778)
							(mid -0.239121 0.213721)
							(end -0.2032 0.2286)
						)
						(arc
							(start 0.2032 0.2286)
							(mid 0.239121 0.213721)
							(end 0.254 0.1778)
						)
						(arc
							(start 0.254 -0.1778)
							(mid 0.239121 -0.213721)
							(end 0.2032 -0.2286)
						)
						(arc
							(start -0.2032 -0.2286)
							(mid -0.239121 -0.213721)
							(end -0.254 -0.1778)
						)
					)
					(width 0)
					(fill yes)
				)
			)
		)
		(pad "2" smd custom
			(at 0 0.4572 270)
			(size 0.1143 0.1143)
			(layers "B.Cu" "B.Mask" "B.Paste")
			(net "GND")
			(options
				(clearance outline)
				(anchor circle)
			)
			(primitives
				(gr_poly
					(pts
						(arc
							(start -0.254 0.1778)
							(mid -0.239121 0.213721)
							(end -0.2032 0.2286)
						)
						(arc
							(start 0.2032 0.2286)
							(mid 0.239121 0.213721)
							(end 0.254 0.1778)
						)
						(arc
							(start 0.254 -0.1778)
							(mid 0.239121 -0.213721)
							(end 0.2032 -0.2286)
						)
						(arc
							(start -0.2032 -0.2286)
							(mid -0.239121 -0.213721)
							(end -0.254 -0.1778)
						)
					)
					(width 0)
					(fill yes)
				)
			)
		)
	)
)
